(kicad_pcb
	(version 20260206)
	(generator "pcbnew")
	(generator_version "10.0")
	(general
		(thickness 1.6)
		(legacy_teardrops no)
	)
	(paper "A4")
	(title_block
		(title "04192023_DAF0TMB3IC0_F0TG_MB_C_brd_V02_OCP.brd")
		(comment 1 "Grand Teton / footprints 6360-6368 of 8354")
	)
	(layers
		(0 "F.Cu" signal "TOP")
		(4 "In1.Cu" signal "GND")
		(6 "In2.Cu" signal "IN1")
		(8 "In3.Cu" signal "GND1")
		(10 "In4.Cu" signal "IN2")
		(12 "In5.Cu" signal "GND2")
		(14 "In6.Cu" signal "IN3")
		(16 "In7.Cu" signal "GND3")
		(18 "In8.Cu" signal "VCC")
		(20 "In9.Cu" signal "VCC1")
		(22 "In10.Cu" signal "GND4")
		(24 "In11.Cu" signal "IN4")
		(26 "In12.Cu" signal "GND5")
		(28 "In13.Cu" signal "IN5")
		(30 "In14.Cu" signal "GND6")
		(32 "In15.Cu" signal "IN6")
		(34 "In16.Cu" signal "GND7")
		(2 "B.Cu" signal "BOTTOM")
		(9 "F.Adhes" user "F.Adhesive")
		(11 "B.Adhes" user "B.Adhesive")
		(13 "F.Paste" user "Package Geometry/Pastemask Top")
		(15 "B.Paste" user "Package Geometry/Pastemask Bottom")
		(5 "F.SilkS" user "Ref Des/Silkscreen Top")
		(7 "B.SilkS" user "Ref Des/Silkscreen Bottom")
		(1 "F.Mask" user "Board Geometry/Soldermask Top")
		(3 "B.Mask" user "Board Geometry/Soldermask Bottom")
		(17 "Dwgs.User" user "User.Drawings")
		(19 "Cmts.User" user "User.Comments")
		(21 "Eco1.User" user "User.Eco1")
		(23 "Eco2.User" user "User.Eco2")
		(25 "Edge.Cuts" user "Board Geometry/Outline")
		(27 "Margin" user)
		(31 "F.CrtYd" user "Package Geometry/Place Bound Top")
		(29 "B.CrtYd" user "Package Geometry/Place Bound Bottom")
		(35 "F.Fab" user "Ref Des/Assembly Top")
		(33 "B.Fab" user "Ref Des/Assembly Bottom")
	)
	(footprint ""
		(layer "B.Cu")
		(at 153.006298 -386.766562 90)
		(property "Reference" "C385"
			(at 0 0 90)
			(layer "B.SilkS")
			(hide yes)
			(effects
				(font
					(size 1.27 1.27)
				)
				(justify mirror)
			)
		)
		(property "Value" ""
			(at 0 0 90)
			(layer "B.Fab")
			(effects
				(font
					(size 1.27 1.27)
				)
				(justify mirror)
			)
		)
		(duplicate_pad_numbers_are_jumpers no)
		(fp_line
			(start 0.299974 -0.150114)
			(end -0.299974 -0.150114)
			(stroke
				(width 0.1)
				(type default)
			)
			(layer "B.Fab")
		)
		(fp_line
			(start -0.299974 -0.150114)
			(end -0.299974 0.150114)
			(stroke
				(width 0.1)
				(type default)
			)
			(layer "B.Fab")
		)
		(fp_line
			(start 0.299974 0.150114)
			(end 0.299974 -0.150114)
			(stroke
				(width 0.1)
				(type default)
			)
			(layer "B.Fab")
		)
		(fp_line
			(start -0.299974 0.150114)
			(end 0.299974 0.150114)
			(stroke
				(width 0.1)
				(type default)
			)
			(layer "B.Fab")
		)
		(pad "1" smd rect
			(at 0.2667 0 270)
			(size 0.3048 0.381)
			(layers "B.Cu" "B.Mask" "B.Paste")
			(net "P0V9_CPU1_RT_2D")
		)
		(pad "2" smd rect
			(at -0.2667 0 270)
			(size 0.3048 0.381)
			(layers "B.Cu" "B.Mask" "B.Paste")
			(net "GND")
		)
	)
	(footprint ""
		(layer "B.Cu")
		(at 337.106006 -395.148562 90)
		(property "Reference" "C647"
			(at 0 0 90)
			(layer "B.SilkS")
			(hide yes)
			(effects
				(font
					(size 1.27 1.27)
				)
				(justify mirror)
			)
		)
		(property "Value" ""
			(at 0 0 90)
			(layer "B.Fab")
			(effects
				(font
					(size 1.27 1.27)
				)
				(justify mirror)
			)
		)
		(duplicate_pad_numbers_are_jumpers no)
		(fp_line
			(start 0.299974 -0.150114)
			(end -0.299974 -0.150114)
			(stroke
				(width 0.1)
				(type default)
			)
			(layer "B.Fab")
		)
		(fp_line
			(start -0.299974 -0.150114)
			(end -0.299974 0.150114)
			(stroke
				(width 0.1)
				(type default)
			)
			(layer "B.Fab")
		)
		(fp_line
			(start 0.299974 0.150114)
			(end 0.299974 -0.150114)
			(stroke
				(width 0.1)
				(type default)
			)
			(layer "B.Fab")
		)
		(fp_line
			(start -0.299974 0.150114)
			(end 0.299974 0.150114)
			(stroke
				(width 0.1)
				(type default)
			)
			(layer "B.Fab")
		)
		(pad "1" smd rect
			(at 0.2667 0 270)
			(size 0.3048 0.381)
			(layers "B.Cu" "B.Mask" "B.Paste")
			(net "P0V9_CPU0_RT1_2A")
		)
		(pad "2" smd rect
			(at -0.2667 0 270)
			(size 0.3048 0.381)
			(layers "B.Cu" "B.Mask" "B.Paste")
			(net "GND")
		)
	)
	(footprint ""
		(layer "B.Cu")
		(at 355.727508 -331.304646 -90)
		(property "Reference" "PC123_6"
			(at 0 0 90)
			(layer "B.SilkS")
			(hide yes)
			(effects
				(font
					(size 1.27 1.27)
				)
				(justify mirror)
			)
		)
		(property "Value" ""
			(at 0 0 90)
			(layer "B.Fab")
			(effects
				(font
					(size 1.27 1.27)
				)
				(justify mirror)
			)
		)
		(duplicate_pad_numbers_are_jumpers no)
		(fp_line
			(start -1.524 0.762)
			(end 1.524 0.762)
			(stroke
				(width 0.1524)
				(type default)
			)
			(layer "B.SilkS")
		)
		(fp_line
			(start 1.524 0.762)
			(end 1.524 -0.762)
			(stroke
				(width 0.1524)
				(type default)
			)
			(layer "B.SilkS")
		)
		(fp_line
			(start -1.524 -0.762)
			(end -1.524 0.762)
			(stroke
				(width 0.1524)
				(type default)
			)
			(layer "B.SilkS")
		)
		(fp_line
			(start 1.524 -0.762)
			(end -1.524 -0.762)
			(stroke
				(width 0.1524)
				(type default)
			)
			(layer "B.SilkS")
		)
		(fp_line
			(start -1.1049 0.724916)
			(end -1.1049 -0.724916)
			(stroke
				(width 0.1)
				(type default)
			)
			(layer "B.Fab")
		)
		(fp_line
			(start 1.1049 0.724916)
			(end -1.1049 0.724916)
			(stroke
				(width 0.1)
				(type default)
			)
			(layer "B.Fab")
		)
		(fp_line
			(start -1.1049 -0.724916)
			(end 1.1049 -0.724916)
			(stroke
				(width 0.1)
				(type default)
			)
			(layer "B.Fab")
		)
		(fp_line
			(start 1.1049 -0.724916)
			(end 1.1049 0.724916)
			(stroke
				(width 0.1)
				(type default)
			)
			(layer "B.Fab")
		)
		(pad "1" smd rect
			(at 0.889 0 270)
			(size 1.016 1.27)
			(layers "B.Cu" "B.Mask" "B.Paste")
			(net "PVDDCR_CPU1_P0")
		)
		(pad "2" smd rect
			(at -0.889 0 270)
			(size 1.016 1.27)
			(layers "B.Cu" "B.Mask" "B.Paste")
			(net "GND")
		)
	)
	(footprint ""
		(layer "B.Cu")
		(at 153.146252 -388.011162 -90)
		(property "Reference" "C383"
			(at 0 0 90)
			(layer "B.SilkS")
			(hide yes)
			(effects
				(font
					(size 1.27 1.27)
				)
				(justify mirror)
			)
		)
		(property "Value" ""
			(at 0 0 90)
			(layer "B.Fab")
			(effects
				(font
					(size 1.27 1.27)
				)
				(justify mirror)
			)
		)
		(duplicate_pad_numbers_are_jumpers no)
		(fp_line
			(start -0.299974 0.150114)
			(end 0.299974 0.150114)
			(stroke
				(width 0.1)
				(type default)
			)
			(layer "B.Fab")
		)
		(fp_line
			(start 0.299974 0.150114)
			(end 0.299974 -0.150114)
			(stroke
				(width 0.1)
				(type default)
			)
			(layer "B.Fab")
		)
		(fp_line
			(start -0.299974 -0.150114)
			(end -0.299974 0.150114)
			(stroke
				(width 0.1)
				(type default)
			)
			(layer "B.Fab")
		)
		(fp_line
			(start 0.299974 -0.150114)
			(end -0.299974 -0.150114)
			(stroke
				(width 0.1)
				(type default)
			)
			(layer "B.Fab")
		)
		(pad "1" smd rect
			(at 0.2667 0 90)
			(size 0.3048 0.381)
			(layers "B.Cu" "B.Mask" "B.Paste")
			(net "P0V9_CPU1_RT_2D")
		)
		(pad "2" smd rect
			(at -0.2667 0 90)
			(size 0.3048 0.381)
			(layers "B.Cu" "B.Mask" "B.Paste")
			(net "GND")
		)
	)
	(footprint ""
		(layer "B.Cu")
		(at 238.633 -335.026 180)
		(property "Reference" "R802"
			(at 0 0 0)
			(layer "B.SilkS")
			(hide yes)
			(effects
				(font
					(size 1.27 1.27)
				)
				(justify mirror)
			)
		)
		(property "Value" ""
			(at 0 0 0)
			(layer "B.Fab")
			(effects
				(font
					(size 1.27 1.27)
				)
				(justify mirror)
			)
		)
		(duplicate_pad_numbers_are_jumpers no)
		(fp_line
			(start 0.32512 0.175006)
			(end 0.32512 -0.175006)
			(stroke
				(width 0.1)
				(type default)
			)
			(layer "B.Fab")
		)
		(fp_line
			(start 0.32512 -0.175006)
			(end -0.32512 -0.175006)
			(stroke
				(width 0.1)
				(type default)
			)
			(layer "B.Fab")
		)
		(fp_line
			(start -0.32512 0.175006)
			(end 0.32512 0.175006)
			(stroke
				(width 0.1)
				(type default)
			)
			(layer "B.Fab")
		)
		(fp_line
			(start -0.32512 -0.175006)
			(end -0.32512 0.175006)
			(stroke
				(width 0.1)
				(type default)
			)
			(layer "B.Fab")
		)
		(pad "1" smd rect
			(at 0.2667 0)
			(size 0.3048 0.381)
			(layers "B.Cu" "B.Mask" "B.Paste")
			(net "SMB_RT_CPU1_P0_ROM_MUX_2D_SCL")
		)
		(pad "2" smd rect
			(at -0.2667 0 180)
			(size 0.3048 0.381)
			(layers "B.Cu" "B.Mask" "B.Paste")
			(net "SMB_RT_CPU1_P0_ROM_MUX_2D_R_SCL")
		)
	)
	(footprint ""
		(layer "B.Cu")
		(at 243.713 -324.866)
		(property "Reference" "C1081"
			(at 0 0 0)
			(layer "B.SilkS")
			(hide yes)
			(effects
				(font
					(size 1.27 1.27)
				)
				(justify mirror)
			)
		)
		(property "Value" ""
			(at 0 0 0)
			(layer "B.Fab")
			(effects
				(font
					(size 1.27 1.27)
				)
				(justify mirror)
			)
		)
		(duplicate_pad_numbers_are_jumpers no)
		(fp_line
			(start -0.7874 -0.4064)
			(end -0.7874 0.4064)
			(stroke
				(width 0.1524)
				(type default)
			)
			(layer "B.SilkS")
		)
		(fp_line
			(start -0.7874 0.4064)
			(end 0.7874 0.4064)
			(stroke
				(width 0.1524)
				(type default)
			)
			(layer "B.SilkS")
		)
		(fp_line
			(start 0.7874 -0.4064)
			(end -0.7874 -0.4064)
			(stroke
				(width 0.1524)
				(type default)
			)
			(layer "B.SilkS")
		)
		(fp_line
			(start 0.7874 0.4064)
			(end 0.7874 -0.4064)
			(stroke
				(width 0.1524)
				(type default)
			)
			(layer "B.SilkS")
		)
		(fp_line
			(start -0.67945 -0.3048)
			(end -0.67945 0.3048)
			(stroke
				(width 0.1)
				(type default)
			)
			(layer "B.Fab")
		)
		(fp_line
			(start -0.67945 0.3048)
			(end -0.120396 0.3048)
			(stroke
				(width 0.1)
				(type default)
			)
			(layer "B.Fab")
		)
		(fp_line
			(start -0.12065 -0.3048)
			(end -0.67945 -0.3048)
			(stroke
				(width 0.1)
				(type default)
			)
			(layer "B.Fab")
		)
		(fp_line
			(start -0.12065 -0.2794)
			(end -0.12065 -0.3048)
			(stroke
				(width 0.1)
				(type default)
			)
			(layer "B.Fab")
		)
		(fp_line
			(start -0.120396 0.2794)
			(end 0.12065 0.2794)
			(stroke
				(width 0.1)
				(type default)
			)
			(layer "B.Fab")
		)
		(fp_line
			(start -0.120396 0.3048)
			(end -0.120396 0.2794)
			(stroke
				(width 0.1)
				(type default)
			)
			(layer "B.Fab")
		)
		(fp_line
			(start 0.12065 -0.305054)
			(end 0.12065 -0.2794)
			(stroke
				(width 0.1)
				(type default)
			)
			(layer "B.Fab")
		)
		(fp_line
			(start 0.12065 -0.2794)
			(end -0.12065 -0.2794)
			(stroke
				(width 0.1)
				(type default)
			)
			(layer "B.Fab")
		)
		(fp_line
			(start 0.12065 0.2794)
			(end 0.12065 0.3048)
			(stroke
				(width 0.1)
				(type default)
			)
			(layer "B.Fab")
		)
		(fp_line
			(start 0.12065 0.3048)
			(end 0.67945 0.3048)
			(stroke
				(width 0.1)
				(type default)
			)
			(layer "B.Fab")
		)
		(fp_line
			(start 0.67945 -0.305054)
			(end 0.12065 -0.305054)
			(stroke
				(width 0.1)
				(type default)
			)
			(layer "B.Fab")
		)
		(fp_line
			(start 0.67945 0.3048)
			(end 0.67945 -0.305054)
			(stroke
				(width 0.1)
				(type default)
			)
			(layer "B.Fab")
		)
		(pad "1" smd circle
			(at 0.40005 0 180)
			(size 0 0)
			(layers "B.Cu" "B.Mask" "B.Paste")
			(net "PVDD18_S5_P1_ADC_MAM")
		)
		(pad "2" smd circle
			(at -0.40005 0 180)
			(size 0 0)
			(layers "B.Cu" "B.Mask" "B.Paste")
			(net "GND")
		)
	)
	(footprint ""
		(layer "B.Cu")
		(at 320.211958 -203.917296 90)
		(property "Reference" "R443"
			(at 0 0 90)
			(layer "B.SilkS")
			(hide yes)
			(effects
				(font
					(size 1.27 1.27)
				)
				(justify mirror)
			)
		)
		(property "Value" ""
			(at 0 0 90)
			(layer "B.Fab")
			(effects
				(font
					(size 1.27 1.27)
				)
				(justify mirror)
			)
		)
		(duplicate_pad_numbers_are_jumpers no)
		(fp_line
			(start 0.7874 -0.4064)
			(end -0.7874 -0.4064)
			(stroke
				(width 0.1524)
				(type default)
			)
			(layer "B.SilkS")
		)
		(fp_line
			(start -0.7874 -0.4064)
			(end -0.7874 0.4064)
			(stroke
				(width 0.1524)
				(type default)
			)
			(layer "B.SilkS")
		)
		(fp_line
			(start 0.7874 0.4064)
			(end 0.7874 -0.4064)
			(stroke
				(width 0.1524)
				(type default)
			)
			(layer "B.SilkS")
		)
		(fp_line
			(start -0.7874 0.4064)
			(end 0.7874 0.4064)
			(stroke
				(width 0.1524)
				(type default)
			)
			(layer "B.SilkS")
		)
		(fp_line
			(start 0.67945 -0.305054)
			(end 0.12065 -0.305054)
			(stroke
				(width 0.1)
				(type default)
			)
			(layer "B.Fab")
		)
		(fp_line
			(start 0.12065 -0.305054)
			(end 0.12065 -0.2794)
			(stroke
				(width 0.1)
				(type default)
			)
			(layer "B.Fab")
		)
		(fp_line
			(start -0.12065 -0.3048)
			(end -0.67945 -0.3048)
			(stroke
				(width 0.1)
				(type default)
			)
			(layer "B.Fab")
		)
		(fp_line
			(start -0.67945 -0.3048)
			(end -0.67945 0.3048)
			(stroke
				(width 0.1)
				(type default)
			)
			(layer "B.Fab")
		)
		(fp_line
			(start 0.12065 -0.2794)
			(end -0.12065 -0.2794)
			(stroke
				(width 0.1)
				(type default)
			)
			(layer "B.Fab")
		)
		(fp_line
			(start -0.12065 -0.2794)
			(end -0.12065 -0.3048)
			(stroke
				(width 0.1)
				(type default)
			)
			(layer "B.Fab")
		)
		(fp_line
			(start 0.12065 0.2794)
			(end 0.12065 0.3048)
			(stroke
				(width 0.1)
				(type default)
			)
			(layer "B.Fab")
		)
		(fp_line
			(start -0.120396 0.2794)
			(end 0.12065 0.2794)
			(stroke
				(width 0.1)
				(type default)
			)
			(layer "B.Fab")
		)
		(fp_line
			(start 0.67945 0.3048)
			(end 0.67945 -0.305054)
			(stroke
				(width 0.1)
				(type default)
			)
			(layer "B.Fab")
		)
		(fp_line
			(start 0.12065 0.3048)
			(end 0.67945 0.3048)
			(stroke
				(width 0.1)
				(type default)
			)
			(layer "B.Fab")
		)
		(fp_line
			(start -0.120396 0.3048)
			(end -0.120396 0.2794)
			(stroke
				(width 0.1)
				(type default)
			)
			(layer "B.Fab")
		)
		(fp_line
			(start -0.67945 0.3048)
			(end -0.120396 0.3048)
			(stroke
				(width 0.1)
				(type default)
			)
			(layer "B.Fab")
		)
		(pad "1" smd circle
			(at 0.40005 0 270)
			(size 0 0)
			(layers "B.Cu" "B.Mask" "B.Paste")
			(net "PWRGD_CPU0_PWROK")
		)
		(pad "2" smd circle
			(at -0.40005 0 270)
			(size 0 0)
			(layers "B.Cu" "B.Mask" "B.Paste")
			(net "PVDD18_S5_P0")
		)
	)
	(footprint ""
		(layer "B.Cu")
		(at 234.569 -240.411 -90)
		(property "Reference" "R1158"
			(at 0 0 90)
			(layer "B.SilkS")
			(hide yes)
			(effects
				(font
					(size 1.27 1.27)
				)
				(justify mirror)
			)
		)
		(property "Value" ""
			(at 0 0 90)
			(layer "B.Fab")
			(effects
				(font
					(size 1.27 1.27)
				)
				(justify mirror)
			)
		)
		(duplicate_pad_numbers_are_jumpers no)
		(fp_line
			(start -0.7874 0.4064)
			(end 0.7874 0.4064)
			(stroke
				(width 0.1524)
				(type default)
			)
			(layer "B.SilkS")
		)
		(fp_line
			(start 0.7874 0.4064)
			(end 0.7874 -0.4064)
			(stroke
				(width 0.1524)
				(type default)
			)
			(layer "B.SilkS")
		)
		(fp_line
			(start -0.7874 -0.4064)
			(end -0.7874 0.4064)
			(stroke
				(width 0.1524)
				(type default)
			)
			(layer "B.SilkS")
		)
		(fp_line
			(start 0.7874 -0.4064)
			(end -0.7874 -0.4064)
			(stroke
				(width 0.1524)
				(type default)
			)
			(layer "B.SilkS")
		)
		(fp_line
			(start -0.67945 0.3048)
			(end -0.120396 0.3048)
			(stroke
				(width 0.1)
				(type default)
			)
			(layer "B.Fab")
		)
		(fp_line
			(start -0.120396 0.3048)
			(end -0.120396 0.2794)
			(stroke
				(width 0.1)
				(type default)
			)
			(layer "B.Fab")
		)
		(fp_line
			(start 0.12065 0.3048)
			(end 0.67945 0.3048)
			(stroke
				(width 0.1)
				(type default)
			)
			(layer "B.Fab")
		)
		(fp_line
			(start 0.67945 0.3048)
			(end 0.67945 -0.305054)
			(stroke
				(width 0.1)
				(type default)
			)
			(layer "B.Fab")
		)
		(fp_line
			(start -0.120396 0.2794)
			(end 0.12065 0.2794)
			(stroke
				(width 0.1)
				(type default)
			)
			(layer "B.Fab")
		)
		(fp_line
			(start 0.12065 0.2794)
			(end 0.12065 0.3048)
			(stroke
				(width 0.1)
				(type default)
			)
			(layer "B.Fab")
		)
		(fp_line
			(start -0.12065 -0.2794)
			(end -0.12065 -0.3048)
			(stroke
				(width 0.1)
				(type default)
			)
			(layer "B.Fab")
		)
		(fp_line
			(start 0.12065 -0.2794)
			(end -0.12065 -0.2794)
			(stroke
				(width 0.1)
				(type default)
			)
			(layer "B.Fab")
		)
		(fp_line
			(start -0.67945 -0.3048)
			(end -0.67945 0.3048)
			(stroke
				(width 0.1)
				(type default)
			)
			(layer "B.Fab")
		)
		(fp_line
			(start -0.12065 -0.3048)
			(end -0.67945 -0.3048)
			(stroke
				(width 0.1)
				(type default)
			)
			(layer "B.Fab")
		)
		(fp_line
			(start 0.12065 -0.305054)
			(end 0.12065 -0.2794)
			(stroke
				(width 0.1)
				(type default)
			)
			(layer "B.Fab")
		)
		(fp_line
			(start 0.67945 -0.305054)
			(end 0.12065 -0.305054)
			(stroke
				(width 0.1)
				(type default)
			)
			(layer "B.Fab")
		)
		(pad "1" smd rect
			(at 0.40005 0 270)
			(size 0.4572 0.508)
			(layers "B.Cu" "B.Mask" "B.Paste")
			(net "SMB_APML_CPU1_R_SDA")
		)
		(pad "2" smd rect
			(at -0.40005 0 270)
			(size 0.4572 0.508)
			(layers "B.Cu" "B.Mask" "B.Paste")
			(net "SMB_APML_CPU1_SDA")
		)
	)
	(footprint ""
		(layer "B.Cu")
		(at 15.113762 -192.362328 90)
		(property "Reference" "R1183"
			(at 0 0 90)
			(layer "B.SilkS")
			(hide yes)
			(effects
				(font
					(size 1.27 1.27)
				)
				(justify mirror)
			)
		)
		(property "Value" ""
			(at 0 0 90)
			(layer "B.Fab")
			(effects
				(font
					(size 1.27 1.27)
				)
				(justify mirror)
			)
		)
		(duplicate_pad_numbers_are_jumpers no)
		(fp_line
			(start 0.7874 -0.4064)
			(end -0.7874 -0.4064)
			(stroke
				(width 0.1524)
				(type default)
			)
			(layer "B.SilkS")
		)
		(fp_line
			(start -0.7874 -0.4064)
			(end -0.7874 0.4064)
			(stroke
				(width 0.1524)
				(type default)
			)
			(layer "B.SilkS")
		)
		(fp_line
			(start 0.7874 0.4064)
			(end 0.7874 -0.4064)
			(stroke
				(width 0.1524)
				(type default)
			)
			(layer "B.SilkS")
		)
		(fp_line
			(start -0.7874 0.4064)
			(end 0.7874 0.4064)
			(stroke
				(width 0.1524)
				(type default)
			)
			(layer "B.SilkS")
		)
		(fp_line
			(start 0.67945 -0.305054)
			(end 0.12065 -0.305054)
			(stroke
				(width 0.1)
				(type default)
			)
			(layer "B.Fab")
		)
		(fp_line
			(start 0.12065 -0.305054)
			(end 0.12065 -0.2794)
			(stroke
				(width 0.1)
				(type default)
			)
			(layer "B.Fab")
		)
		(fp_line
			(start -0.12065 -0.3048)
			(end -0.67945 -0.3048)
			(stroke
				(width 0.1)
				(type default)
			)
			(layer "B.Fab")
		)
		(fp_line
			(start -0.67945 -0.3048)
			(end -0.67945 0.3048)
			(stroke
				(width 0.1)
				(type default)
			)
			(layer "B.Fab")
		)
		(fp_line
			(start 0.12065 -0.2794)
			(end -0.12065 -0.2794)
			(stroke
				(width 0.1)
				(type default)
			)
			(layer "B.Fab")
		)
		(fp_line
			(start -0.12065 -0.2794)
			(end -0.12065 -0.3048)
			(stroke
				(width 0.1)
				(type default)
			)
			(layer "B.Fab")
		)
		(fp_line
			(start 0.12065 0.2794)
			(end 0.12065 0.3048)
			(stroke
				(width 0.1)
				(type default)
			)
			(layer "B.Fab")
		)
		(fp_line
			(start -0.120396 0.2794)
			(end 0.12065 0.2794)
			(stroke
				(width 0.1)
				(type default)
			)
			(layer "B.Fab")
		)
		(fp_line
			(start 0.67945 0.3048)
			(end 0.67945 -0.305054)
			(stroke
				(width 0.1)
				(type default)
			)
			(layer "B.Fab")
		)
		(fp_line
			(start 0.12065 0.3048)
			(end 0.67945 0.3048)
			(stroke
				(width 0.1)
				(type default)
			)
			(layer "B.Fab")
		)
		(fp_line
			(start -0.120396 0.3048)
			(end -0.120396 0.2794)
			(stroke
				(width 0.1)
				(type default)
			)
			(layer "B.Fab")
		)
		(fp_line
			(start -0.67945 0.3048)
			(end -0.120396 0.3048)
			(stroke
				(width 0.1)
				(type default)
			)
			(layer "B.Fab")
		)
		(pad "1" smd circle
			(at 0.40005 0 270)
			(size 0 0)
			(layers "B.Cu" "B.Mask" "B.Paste")
			(net "PWRGD_CHF_CPU1_DIMM")
		)
		(pad "2" smd circle
			(at -0.40005 0 270)
			(size 0 0)
			(layers "B.Cu" "B.Mask" "B.Paste")
			(net "PWRGD_CHAF_CPU1")
		)
	)
)
